# BASEBOARD_FAB2 (Tioga Pass) — schematic netlist excerpt (pin names and nets, part order shuffled) for the footprints in the layout excerpt that follows; sources: Cadence DE-HDL packaged netlist, KiCad conversion of Wiwynn_Tioga_Pass_MB.brd

C9N5  CAP  0.22UF 16V 10% X7R  pkg 0402  page 182 : A = P3E_CPU1_PE3_MP_C_TXP<13> ; B = P3E_CPU1_PE3_MP_TXP<13>
C6L6  CAP_A  0.01UF 25V 10% X7R  pkg 0402V  page 51 : A = M_E_VREF ; B = GND
U25W15  TTL1G07_A  74LVC1G07 IC  pkg SOP  page 255 : A = BMC_DEBUG_EN_N ; Y = CPU_XDP_PRESENT_N

(kicad_pcb
	(version 20260206)
	(generator "pcbnew")
	(generator_version "10.0")
	(general
		(thickness 1.6)
		(legacy_teardrops no)
	)
	(paper "A4")
	(title_block
		(title "Wiwynn_Tioga_Pass_MB.brd")
		(comment 1 "Tioga Pass / footprints 3990-3992 of 4770")
	)
	(layers
		(0 "F.Cu" signal "TOP")
		(4 "In1.Cu" signal "L2GND")
		(6 "In2.Cu" signal "L3")
		(8 "In3.Cu" signal "L4GND")
		(10 "In4.Cu" signal "L5")
		(12 "In5.Cu" signal "L6GND")
		(14 "In6.Cu" signal "L7VCC")
		(16 "In7.Cu" signal "L8VCC")
		(18 "In8.Cu" signal "L9GND")
		(20 "In9.Cu" signal "L10")
		(22 "In10.Cu" signal "L11GND")
		(24 "In11.Cu" signal "L12")
		(26 "In12.Cu" signal "L13GND")
		(2 "B.Cu" signal "BOTTOM")
		(9 "F.Adhes" user "F.Adhesive")
		(11 "B.Adhes" user "B.Adhesive")
		(13 "F.Paste" user "Package Geometry/Pastemask Top")
		(15 "B.Paste" user "Package Geometry/Pastemask Bottom")
		(5 "F.SilkS" user "Ref Des/Silkscreen Top")
		(7 "B.SilkS" user "Ref Des/Silkscreen Bottom")
		(1 "F.Mask" user "Board Geometry/Soldermask Top")
		(3 "B.Mask" user "Board Geometry/Soldermask Bottom")
		(17 "Dwgs.User" user "User.Drawings")
		(19 "Cmts.User" user "User.Comments")
		(21 "Eco1.User" user "User.Eco1")
		(23 "Eco2.User" user "User.Eco2")
		(25 "Edge.Cuts" user "Board Geometry/Outline")
		(27 "Margin" user)
		(31 "F.CrtYd" user "Package Geometry/Place Bound Top")
		(29 "B.CrtYd" user "Package Geometry/Place Bound Bottom")
		(35 "F.Fab" user "Ref Des/Assembly Top")
		(33 "B.Fab" user "Ref Des/Assembly Bottom")
	)
	(footprint ""
		(layer "B.Cu")
		(at 17.83842 -106.09072 90)
		(property "Reference" "C9N5"
			(at 0 0 90)
			(layer "B.SilkS")
			(hide yes)
			(effects
				(font
					(size 1.27 1.27)
				)
				(justify mirror)
			)
		)
		(property "Value" ""
			(at 0 0 90)
			(layer "B.Fab")
			(effects
				(font
					(size 1.27 1.27)
				)
				(justify mirror)
			)
		)
		(duplicate_pad_numbers_are_jumpers no)
		(fp_poly
			(pts
				(xy -0.3048 -0.1016) (xy -0.3048 0.9906) (xy 0.3048 0.9906) (xy 0.3048 -0.1016)
			)
			(stroke
				(width 0)
				(type default)
			)
			(fill no)
			(layer "B.CrtYd")
		)
		(fp_line
			(start 0.3048 -0.1016)
			(end 0.3048 0.9906)
			(stroke
				(width 0.1)
				(type default)
			)
			(layer "B.Fab")
		)
		(fp_line
			(start -0.3048 -0.1016)
			(end 0.3048 -0.1016)
			(stroke
				(width 0.1)
				(type default)
			)
			(layer "B.Fab")
		)
		(fp_line
			(start 0.3048 0.9906)
			(end -0.3048 0.9906)
			(stroke
				(width 0.1)
				(type default)
			)
			(layer "B.Fab")
		)
		(fp_line
			(start -0.3048 0.9906)
			(end -0.3048 -0.1016)
			(stroke
				(width 0.1)
				(type default)
			)
			(layer "B.Fab")
		)
		(pad "1" smd rect
			(at 0 0 270)
			(size 0.508 0.508)
			(layers "B.Cu" "B.Mask" "B.Paste")
			(net "P3E_CPU1_PE3_MP_C_TXP<13>")
		)
		(pad "2" smd rect
			(at 0 0.889 270)
			(size 0.508 0.508)
			(layers "B.Cu" "B.Mask" "B.Paste")
			(net "P3E_CPU1_PE3_MP_TXP<13>")
		)
		(zone
			(layer "B.Cu")
			(hatch none 0.5)
			(connect_pads
				(clearance 0)
			)
			(min_thickness 0.25)
			(keepout
				(tracks allowed)
				(vias not_allowed)
				(pads allowed)
				(copperpour not_allowed)
				(footprints allowed)
			)
			(placement
				(enabled no)
				(sheetname "")
			)
			(fill
				(thermal_gap 0.5)
				(thermal_bridge_width 0.5)
				(island_removal_mode 0)
			)
			(polygon
				(pts
					(xy 18.09242 -106.34472) (xy 18.09242 -105.83672) (xy 18.47342 -105.83672) (xy 18.47342 -106.34472)
				)
			)
		)
		(zone
			(layer "B.Cu")
			(hatch none 0.5)
			(connect_pads
				(clearance 0)
			)
			(min_thickness 0.25)
			(keepout
				(tracks not_allowed)
				(vias allowed)
				(pads allowed)
				(copperpour not_allowed)
				(footprints allowed)
			)
			(placement
				(enabled no)
				(sheetname "")
			)
			(fill
				(thermal_gap 0.5)
				(thermal_bridge_width 0.5)
				(island_removal_mode 0)
			)
			(polygon
				(pts
					(xy 18.47342 -106.34472) (xy 18.47342 -105.83672) (xy 18.09242 -105.83672) (xy 18.09242 -106.34472)
				)
			)
		)
	)
	(footprint ""
		(layer "B.Cu")
		(at 195.453 -144.977612 90)
		(property "Reference" "C6L6"
			(at 0 0 90)
			(layer "B.SilkS")
			(hide yes)
			(effects
				(font
					(size 1.27 1.27)
				)
				(justify mirror)
			)
		)
		(property "Value" ""
			(at 0 0 90)
			(layer "B.Fab")
			(effects
				(font
					(size 1.27 1.27)
				)
				(justify mirror)
			)
		)
		(duplicate_pad_numbers_are_jumpers no)
		(fp_poly
			(pts
				(xy -0.3048 -0.1016) (xy -0.3048 0.9906) (xy 0.3048 0.9906) (xy 0.3048 -0.1016)
			)
			(stroke
				(width 0)
				(type default)
			)
			(fill no)
			(layer "B.CrtYd")
		)
		(fp_line
			(start 0.3048 -0.1016)
			(end 0.3048 0.9906)
			(stroke
				(width 0.1)
				(type default)
			)
			(layer "B.Fab")
		)
		(fp_line
			(start -0.3048 -0.1016)
			(end 0.3048 -0.1016)
			(stroke
				(width 0.1)
				(type default)
			)
			(layer "B.Fab")
		)
		(fp_line
			(start 0.3048 0.9906)
			(end -0.3048 0.9906)
			(stroke
				(width 0.1)
				(type default)
			)
			(layer "B.Fab")
		)
		(fp_line
			(start -0.3048 0.9906)
			(end -0.3048 -0.1016)
			(stroke
				(width 0.1)
				(type default)
			)
			(layer "B.Fab")
		)
		(pad "1" smd rect
			(at 0 0 270)
			(size 0.508 0.508)
			(layers "B.Cu" "B.Mask" "B.Paste")
			(net "M_E_VREF")
		)
		(pad "2" smd rect
			(at 0 0.889 270)
			(size 0.508 0.508)
			(layers "B.Cu" "B.Mask" "B.Paste")
			(net "GND")
		)
		(zone
			(layer "B.Cu")
			(hatch none 0.5)
			(connect_pads
				(clearance 0)
			)
			(min_thickness 0.25)
			(keepout
				(tracks allowed)
				(vias not_allowed)
				(pads allowed)
				(copperpour not_allowed)
				(footprints allowed)
			)
			(placement
				(enabled no)
				(sheetname "")
			)
			(fill
				(thermal_gap 0.5)
				(thermal_bridge_width 0.5)
				(island_removal_mode 0)
			)
			(polygon
				(pts
					(xy 195.707 -145.231612) (xy 195.707 -144.723612) (xy 196.088 -144.723612) (xy 196.088 -145.231612)
				)
			)
		)
		(zone
			(layer "B.Cu")
			(hatch none 0.5)
			(connect_pads
				(clearance 0)
			)
			(min_thickness 0.25)
			(keepout
				(tracks not_allowed)
				(vias allowed)
				(pads allowed)
				(copperpour not_allowed)
				(footprints allowed)
			)
			(placement
				(enabled no)
				(sheetname "")
			)
			(fill
				(thermal_gap 0.5)
				(thermal_bridge_width 0.5)
				(island_removal_mode 0)
			)
			(polygon
				(pts
					(xy 196.088 -145.231612) (xy 196.088 -144.723612) (xy 195.707 -144.723612) (xy 195.707 -145.231612)
				)
			)
		)
	)
	(footprint ""
		(layer "B.Cu")
		(at 444.701168 -146.393662 180)
		(property "Reference" "U25W15"
			(at 0.14986 2.621788 180)
			(unlocked yes)
			(layer "B.SilkS")
			(effects
				(font
					(size 1.27 0.964946)
					(thickness 0.000001)
				)
				(justify left mirror)
			)
		)
		(property "Value" ""
			(at 0 0 0)
			(layer "B.Fab")
			(effects
				(font
					(size 1.27 1.27)
				)
				(justify mirror)
			)
		)
		(duplicate_pad_numbers_are_jumpers no)
		(fp_circle
			(center 0.4699 -0.8382)
			(end 0.3429 -0.8382)
			(stroke
				(width 0.254)
				(type default)
			)
			(fill no)
			(layer "B.SilkS")
		)
		(fp_poly
			(pts
				(xy -0.21463 -0.450088) (xy -1.56337 -0.450088) (xy -1.56337 1.75006) (xy -0.21463 1.75006)
			)
			(stroke
				(width 0)
				(type default)
			)
			(fill no)
			(layer "B.CrtYd")
		)
		(fp_line
			(start -0.21463 1.75006)
			(end -0.21463 -0.450088)
			(stroke
				(width 0.1)
				(type default)
			)
			(layer "B.Fab")
		)
		(fp_line
			(start -0.21463 -0.450088)
			(end -1.56337 -0.450088)
			(stroke
				(width 0.1)
				(type default)
			)
			(layer "B.Fab")
		)
		(fp_line
			(start -1.56337 1.75006)
			(end -0.21463 1.75006)
			(stroke
				(width 0.1)
				(type default)
			)
			(layer "B.Fab")
		)
		(fp_line
			(start -1.56337 -0.450088)
			(end -1.56337 1.75006)
			(stroke
				(width 0.1)
				(type default)
			)
			(layer "B.Fab")
		)
		(fp_circle
			(center 0.4699 -0.8382)
			(end 0.3429 -0.8382)
			(stroke
				(width 0.254)
				(type default)
			)
			(fill no)
			(layer "B.Fab")
		)
		(pad "1" smd rect
			(at 0 0)
			(size 1.016 0.381)
			(layers "B.Cu" "B.Mask" "B.Paste")
			(net "Net_6508")
		)
		(pad "2" smd rect
			(at 0 0.649986)
			(size 1.016 0.381)
			(layers "B.Cu" "B.Mask" "B.Paste")
			(net "BMC_DEBUG_EN_N")
		)
		(pad "3" smd rect
			(at 0 1.299972)
			(size 1.016 0.381)
			(layers "B.Cu" "B.Mask" "B.Paste")
			(net "GND")
		)
		(pad "4" smd rect
			(at -1.778 1.299972)
			(size 1.016 0.381)
			(layers "B.Cu" "B.Mask" "B.Paste")
			(net "CPU_XDP_PRESENT_N")
		)
		(pad "5" smd rect
			(at -1.778 0)
			(size 1.016 0.381)
			(layers "B.Cu" "B.Mask" "B.Paste")
			(net "P3V3_STBY")
		)
	)
)
